(kicad_pcb
	(version 20260206)
	(generator "pcbnew")
	(generator_version "10.0")
	(general
		(thickness 1.6)
		(legacy_teardrops no)
	)
	(paper "A4")
	(title_block
		(title "15969-1a.1015WZS0858.brd")
		(comment 1 "Tioga Pass / footprint 93 of 295 (SLOT2), pads 76-150 of 166")
	)
	(layers
		(0 "F.Cu" signal "TOP")
		(4 "In1.Cu" signal "L2GND")
		(6 "In2.Cu" signal "L3")
		(8 "In3.Cu" signal "L4")
		(10 "In4.Cu" signal "L5GND")
		(2 "B.Cu" signal "BOTTOM")
		(9 "F.Adhes" user "F.Adhesive")
		(11 "B.Adhes" user "B.Adhesive")
		(13 "F.Paste" user "Package Geometry/Pastemask Top")
		(15 "B.Paste" user "Package Geometry/Pastemask Bottom")
		(5 "F.SilkS" user "Ref Des/Silkscreen Top")
		(7 "B.SilkS" user "Ref Des/Silkscreen Bottom")
		(1 "F.Mask" user "Board Geometry/Soldermask Top")
		(3 "B.Mask" user "Board Geometry/Soldermask Bottom")
		(17 "Dwgs.User" user "User.Drawings")
		(19 "Cmts.User" user "User.Comments")
		(21 "Eco1.User" user "User.Eco1")
		(23 "Eco2.User" user "User.Eco2")
		(25 "Edge.Cuts" user "Board Geometry/Outline")
		(27 "Margin" user)
		(31 "F.CrtYd" user "Package Geometry/Place Bound Top")
		(29 "B.CrtYd" user "Package Geometry/Place Bound Bottom")
		(35 "F.Fab" user "Ref Des/Assembly Top")
		(33 "B.Fab" user "Ref Des/Assembly Bottom")
	)
	(footprint ""
		(layer "F.Cu")
		(at 42.729912 -10.500106)
		(property "Reference" "SLOT2"
			(at 0 0 0)
			(layer "F.SilkS")
			(hide yes)
			(effects
				(font
					(size 1.27 1.27)
				)
			)
		)
		(property "Value" "PCISLT164-129-GP"
			(at -15.9639 4.8514 0)
			(unlocked yes)
			(layer "F.Fab")
			(hide yes)
			(effects
				(font
					(size 1.016 1.016)
					(thickness 0.1524)
				)
			)
		)
		(property "Device Type" "10018783-10203TLF"
			(at -15.9639 3.3274 0)
			(unlocked yes)
			(layer "F.Fab")
			(hide yes)
			(effects
				(font
					(size 1.016 1.016)
					(thickness 0.1524)
				)
			)
		)
		(duplicate_pad_numbers_are_jumpers no)
		(pad "A74" thru_hole circle
			(at 63.35014 -3.24993)
			(size 1.0668 1.0668)
			(drill 0.7112)
			(layers "*.Cu" "*.Mask")
			(remove_unused_layers no)
			(net "GND")
			(clearance 0.1778)
			(thermal_gap 0.1778)
		)
		(pad "A75" thru_hole circle
			(at 64.34963 -1.24968)
			(size 1.0668 1.0668)
			(drill 0.7112)
			(layers "*.Cu" "*.Mask")
			(remove_unused_layers no)
			(net "GND")
			(clearance 0.1778)
			(thermal_gap 0.1778)
		)
		(pad "A76" thru_hole circle
			(at 65.35039 -3.24993)
			(size 1.0668 1.0668)
			(drill 0.7112)
			(layers "*.Cu" "*.Mask")
			(remove_unused_layers no)
			(net "P3E_CPU0_PE1_SS_C_RXP<1>")
			(clearance 0.1778)
			(thermal_gap 0.1778)
		)
		(pad "A77" thru_hole circle
			(at 66.34988 -1.24968)
			(size 1.0668 1.0668)
			(drill 0.7112)
			(layers "*.Cu" "*.Mask")
			(remove_unused_layers no)
			(net "P3E_CPU0_PE1_SS_C_RXN<1>")
			(clearance 0.1778)
			(thermal_gap 0.1778)
		)
		(pad "A78" thru_hole circle
			(at 67.34937 -3.24993)
			(size 1.0668 1.0668)
			(drill 0.7112)
			(layers "*.Cu" "*.Mask")
			(remove_unused_layers no)
			(net "GND")
			(clearance 0.1778)
			(thermal_gap 0.1778)
		)
		(pad "A79" thru_hole circle
			(at 68.35013 -1.24968)
			(size 1.0668 1.0668)
			(drill 0.7112)
			(layers "*.Cu" "*.Mask")
			(remove_unused_layers no)
			(net "GND")
			(clearance 0.1778)
			(thermal_gap 0.1778)
		)
		(pad "A80" thru_hole circle
			(at 69.34962 -3.24993)
			(size 1.0668 1.0668)
			(drill 0.7112)
			(layers "*.Cu" "*.Mask")
			(remove_unused_layers no)
			(net "P3E_CPU0_PE1_SS_C_RXP<0>")
			(clearance 0.1778)
			(thermal_gap 0.1778)
		)
		(pad "A81" thru_hole circle
			(at 70.35038 -1.24968)
			(size 1.0668 1.0668)
			(drill 0.7112)
			(layers "*.Cu" "*.Mask")
			(remove_unused_layers no)
			(net "P3E_CPU0_PE1_SS_C_RXN<0>")
			(clearance 0.1778)
			(thermal_gap 0.1778)
		)
		(pad "A82" thru_hole circle
			(at 71.34987 -3.24993)
			(size 1.0668 1.0668)
			(drill 0.7112)
			(layers "*.Cu" "*.Mask")
			(remove_unused_layers no)
			(net "GND")
			(clearance 0.1778)
			(thermal_gap 0.1778)
		)
		(pad "B1" thru_hole circle
			(at -11.64971 1.24968)
			(size 1.0668 1.0668)
			(drill 0.7112)
			(layers "*.Cu" "*.Mask")
			(remove_unused_layers no)
			(net "P12V_SLOT2")
			(clearance 0.1778)
			(thermal_gap 0.1778)
		)
		(pad "B2" thru_hole circle
			(at -10.65022 3.24993)
			(size 1.0668 1.0668)
			(drill 0.7112)
			(layers "*.Cu" "*.Mask")
			(remove_unused_layers no)
			(net "P12V_SLOT2")
			(clearance 0.1778)
			(thermal_gap 0.1778)
		)
		(pad "B3" thru_hole circle
			(at -9.64946 1.24968)
			(size 1.0668 1.0668)
			(drill 0.7112)
			(layers "*.Cu" "*.Mask")
			(remove_unused_layers no)
			(net "P12V_SLOT2")
			(clearance 0.1778)
			(thermal_gap 0.1778)
		)
		(pad "B4" thru_hole circle
			(at -8.64997 3.24993)
			(size 1.0668 1.0668)
			(drill 0.7112)
			(layers "*.Cu" "*.Mask")
			(remove_unused_layers no)
			(net "GND")
			(clearance 0.1778)
			(thermal_gap 0.1778)
		)
		(pad "B5" thru_hole circle
			(at -7.65048 1.24968)
			(size 1.0668 1.0668)
			(drill 0.7112)
			(layers "*.Cu" "*.Mask")
			(remove_unused_layers no)
			(net "SMCLK_BMC_SLOT2_R")
			(clearance 0.1778)
			(thermal_gap 0.1778)
		)
		(pad "B6" thru_hole circle
			(at -6.64972 3.24993)
			(size 1.0668 1.0668)
			(drill 0.7112)
			(layers "*.Cu" "*.Mask")
			(remove_unused_layers no)
			(net "SMDAT_BMC_SLOT2_R")
			(clearance 0.1778)
			(thermal_gap 0.1778)
		)
		(pad "B7" thru_hole circle
			(at -5.65023 1.24968)
			(size 1.0668 1.0668)
			(drill 0.7112)
			(layers "*.Cu" "*.Mask")
			(remove_unused_layers no)
			(net "GND")
			(clearance 0.1778)
			(thermal_gap 0.1778)
		)
		(pad "B8" thru_hole circle
			(at -4.64947 3.24993)
			(size 1.0668 1.0668)
			(drill 0.7112)
			(layers "*.Cu" "*.Mask")
			(remove_unused_layers no)
			(net "P3V3")
			(clearance 0.1778)
			(thermal_gap 0.1778)
		)
		(pad "B9" thru_hole circle
			(at -3.64998 1.24968)
			(size 1.0668 1.0668)
			(drill 0.7112)
			(layers "*.Cu" "*.Mask")
			(remove_unused_layers no)
			(net "Net_101")
			(clearance 0.1778)
			(thermal_gap 0.1778)
		)
		(pad "B10" thru_hole circle
			(at -2.65049 3.24993)
			(size 1.0668 1.0668)
			(drill 0.7112)
			(layers "*.Cu" "*.Mask")
			(remove_unused_layers no)
			(net "P3V3_STBY")
			(clearance 0.1778)
			(thermal_gap 0.1778)
		)
		(pad "B11" thru_hole circle
			(at -1.64973 1.24968)
			(size 1.0668 1.0668)
			(drill 0.7112)
			(layers "*.Cu" "*.Mask")
			(remove_unused_layers no)
			(net "FM_PE_SLOTX24_WAKE_N")
			(clearance 0.1778)
			(thermal_gap 0.1778)
		)
		(pad "B12" thru_hole circle
			(at 1.35001 3.24993)
			(size 1.0668 1.0668)
			(drill 0.7112)
			(layers "*.Cu" "*.Mask")
			(remove_unused_layers no)
			(net "SMB_ALERT_S2_B12_N")
			(clearance 0.1778)
			(thermal_gap 0.1778)
		)
		(pad "B13" thru_hole circle
			(at 2.3495 1.24968)
			(size 1.0668 1.0668)
			(drill 0.7112)
			(layers "*.Cu" "*.Mask")
			(remove_unused_layers no)
			(net "GND")
			(clearance 0.1778)
			(thermal_gap 0.1778)
		)
		(pad "B14" thru_hole circle
			(at 3.35026 3.24993)
			(size 1.0668 1.0668)
			(drill 0.7112)
			(layers "*.Cu" "*.Mask")
			(remove_unused_layers no)
			(net "P3E_CPU0_PE1_PCH_CON_TXP<15>")
			(clearance 0.1778)
			(thermal_gap 0.1778)
		)
		(pad "B15" thru_hole circle
			(at 4.34975 1.24968)
			(size 1.0668 1.0668)
			(drill 0.7112)
			(layers "*.Cu" "*.Mask")
			(remove_unused_layers no)
			(net "P3E_CPU0_PE1_PCH_CON_TXN<15>")
			(clearance 0.1778)
			(thermal_gap 0.1778)
		)
		(pad "B16" thru_hole circle
			(at 5.35051 3.24993)
			(size 1.0668 1.0668)
			(drill 0.7112)
			(layers "*.Cu" "*.Mask")
			(remove_unused_layers no)
			(net "GND")
			(clearance 0.1778)
			(thermal_gap 0.1778)
		)
		(pad "B17" thru_hole circle
			(at 6.35 1.24968)
			(size 1.0668 1.0668)
			(drill 0.7112)
			(layers "*.Cu" "*.Mask")
			(remove_unused_layers no)
			(net "PCIE_SLOT2_PRSNT2_1_N")
			(clearance 0.1778)
			(thermal_gap 0.1778)
		)
		(pad "B18" thru_hole circle
			(at 7.34949 3.24993)
			(size 1.0668 1.0668)
			(drill 0.7112)
			(layers "*.Cu" "*.Mask")
			(remove_unused_layers no)
			(net "GND")
			(clearance 0.1778)
			(thermal_gap 0.1778)
		)
		(pad "B19" thru_hole circle
			(at 8.35025 1.24968)
			(size 1.0668 1.0668)
			(drill 0.7112)
			(layers "*.Cu" "*.Mask")
			(remove_unused_layers no)
			(net "P3E_CPU0_PE1_PCH_CON_TXP<14>")
			(clearance 0.1778)
			(thermal_gap 0.1778)
		)
		(pad "B20" thru_hole circle
			(at 9.34974 3.24993)
			(size 1.0668 1.0668)
			(drill 0.7112)
			(layers "*.Cu" "*.Mask")
			(remove_unused_layers no)
			(net "P3E_CPU0_PE1_PCH_CON_TXN<14>")
			(clearance 0.1778)
			(thermal_gap 0.1778)
		)
		(pad "B21" thru_hole circle
			(at 10.3505 1.24968)
			(size 1.0668 1.0668)
			(drill 0.7112)
			(layers "*.Cu" "*.Mask")
			(remove_unused_layers no)
			(net "GND")
			(clearance 0.1778)
			(thermal_gap 0.1778)
		)
		(pad "B22" thru_hole circle
			(at 11.34999 3.24993)
			(size 1.0668 1.0668)
			(drill 0.7112)
			(layers "*.Cu" "*.Mask")
			(remove_unused_layers no)
			(net "GND")
			(clearance 0.1778)
			(thermal_gap 0.1778)
		)
		(pad "B23" thru_hole circle
			(at 12.34948 1.24968)
			(size 1.0668 1.0668)
			(drill 0.7112)
			(layers "*.Cu" "*.Mask")
			(remove_unused_layers no)
			(net "P3E_CPU0_PE1_PCH_CON_TXP<13>")
			(clearance 0.1778)
			(thermal_gap 0.1778)
		)
		(pad "B24" thru_hole circle
			(at 13.35024 3.24993)
			(size 1.0668 1.0668)
			(drill 0.7112)
			(layers "*.Cu" "*.Mask")
			(remove_unused_layers no)
			(net "P3E_CPU0_PE1_PCH_CON_TXN<13>")
			(clearance 0.1778)
			(thermal_gap 0.1778)
		)
		(pad "B25" thru_hole circle
			(at 14.34973 1.24968)
			(size 1.0668 1.0668)
			(drill 0.7112)
			(layers "*.Cu" "*.Mask")
			(remove_unused_layers no)
			(net "GND")
			(clearance 0.1778)
			(thermal_gap 0.1778)
		)
		(pad "B26" thru_hole circle
			(at 15.35049 3.24993)
			(size 1.0668 1.0668)
			(drill 0.7112)
			(layers "*.Cu" "*.Mask")
			(remove_unused_layers no)
			(net "GND")
			(clearance 0.1778)
			(thermal_gap 0.1778)
		)
		(pad "B27" thru_hole circle
			(at 16.34998 1.24968)
			(size 1.0668 1.0668)
			(drill 0.7112)
			(layers "*.Cu" "*.Mask")
			(remove_unused_layers no)
			(net "P3E_CPU0_PE1_PCH_CON_TXP<12>")
			(clearance 0.1778)
			(thermal_gap 0.1778)
		)
		(pad "B28" thru_hole circle
			(at 17.34947 3.24993)
			(size 1.0668 1.0668)
			(drill 0.7112)
			(layers "*.Cu" "*.Mask")
			(remove_unused_layers no)
			(net "P3E_CPU0_PE1_PCH_CON_TXN<12>")
			(clearance 0.1778)
			(thermal_gap 0.1778)
		)
		(pad "B29" thru_hole circle
			(at 18.35023 1.24968)
			(size 1.0668 1.0668)
			(drill 0.7112)
			(layers "*.Cu" "*.Mask")
			(remove_unused_layers no)
			(net "GND")
			(clearance 0.1778)
			(thermal_gap 0.1778)
		)
		(pad "B30" thru_hole circle
			(at 19.34972 3.24993)
			(size 1.0668 1.0668)
			(drill 0.7112)
			(layers "*.Cu" "*.Mask")
			(remove_unused_layers no)
			(net "FM_PWRBRK_SLOT_N")
			(clearance 0.1778)
			(thermal_gap 0.1778)
		)
		(pad "B31" thru_hole circle
			(at 20.35048 1.24968)
			(size 1.0668 1.0668)
			(drill 0.7112)
			(layers "*.Cu" "*.Mask")
			(remove_unused_layers no)
			(net "PCIE_SLOT2_PRSNT2_2_N")
			(clearance 0.1778)
			(thermal_gap 0.1778)
		)
		(pad "B32" thru_hole circle
			(at 21.34997 3.24993)
			(size 1.0668 1.0668)
			(drill 0.7112)
			(layers "*.Cu" "*.Mask")
			(remove_unused_layers no)
			(net "GND")
			(clearance 0.1778)
			(thermal_gap 0.1778)
		)
		(pad "B33" thru_hole circle
			(at 22.34946 1.24968)
			(size 1.0668 1.0668)
			(drill 0.7112)
			(layers "*.Cu" "*.Mask")
			(remove_unused_layers no)
			(net "P3E_CPU0_PE1_PCH_CON_TXP<11>")
			(clearance 0.1778)
			(thermal_gap 0.1778)
		)
		(pad "B34" thru_hole circle
			(at 23.35022 3.24993)
			(size 1.0668 1.0668)
			(drill 0.7112)
			(layers "*.Cu" "*.Mask")
			(remove_unused_layers no)
			(net "P3E_CPU0_PE1_PCH_CON_TXN<11>")
			(clearance 0.1778)
			(thermal_gap 0.1778)
		)
		(pad "B35" thru_hole circle
			(at 24.34971 1.24968)
			(size 1.0668 1.0668)
			(drill 0.7112)
			(layers "*.Cu" "*.Mask")
			(remove_unused_layers no)
			(net "GND")
			(clearance 0.1778)
			(thermal_gap 0.1778)
		)
		(pad "B36" thru_hole circle
			(at 25.35047 3.24993)
			(size 1.0668 1.0668)
			(drill 0.7112)
			(layers "*.Cu" "*.Mask")
			(remove_unused_layers no)
			(net "GND")
			(clearance 0.1778)
			(thermal_gap 0.1778)
		)
		(pad "B37" thru_hole circle
			(at 26.34996 1.24968)
			(size 1.0668 1.0668)
			(drill 0.7112)
			(layers "*.Cu" "*.Mask")
			(remove_unused_layers no)
			(net "P3E_CPU0_PE1_PCH_CON_TXP<10>")
			(clearance 0.1778)
			(thermal_gap 0.1778)
		)
		(pad "B38" thru_hole circle
			(at 27.34945 3.24993)
			(size 1.0668 1.0668)
			(drill 0.7112)
			(layers "*.Cu" "*.Mask")
			(remove_unused_layers no)
			(net "P3E_CPU0_PE1_PCH_CON_TXN<10>")
			(clearance 0.1778)
			(thermal_gap 0.1778)
		)
		(pad "B39" thru_hole circle
			(at 28.35021 1.24968)
			(size 1.0668 1.0668)
			(drill 0.7112)
			(layers "*.Cu" "*.Mask")
			(remove_unused_layers no)
			(net "GND")
			(clearance 0.1778)
			(thermal_gap 0.1778)
		)
		(pad "B40" thru_hole circle
			(at 29.3497 3.24993)
			(size 1.0668 1.0668)
			(drill 0.7112)
			(layers "*.Cu" "*.Mask")
			(remove_unused_layers no)
			(net "GND")
			(clearance 0.1778)
			(thermal_gap 0.1778)
		)
		(pad "B41" thru_hole circle
			(at 30.35046 1.24968)
			(size 1.0668 1.0668)
			(drill 0.7112)
			(layers "*.Cu" "*.Mask")
			(remove_unused_layers no)
			(net "P3E_CPU0_PE1_PCH_CON_TXP<9>")
			(clearance 0.1778)
			(thermal_gap 0.1778)
		)
		(pad "B42" thru_hole circle
			(at 31.34995 3.24993)
			(size 1.0668 1.0668)
			(drill 0.7112)
			(layers "*.Cu" "*.Mask")
			(remove_unused_layers no)
			(net "P3E_CPU0_PE1_PCH_CON_TXN<9>")
			(clearance 0.1778)
			(thermal_gap 0.1778)
		)
		(pad "B43" thru_hole circle
			(at 32.34944 1.24968)
			(size 1.0668 1.0668)
			(drill 0.7112)
			(layers "*.Cu" "*.Mask")
			(remove_unused_layers no)
			(net "GND")
			(clearance 0.1778)
			(thermal_gap 0.1778)
		)
		(pad "B44" thru_hole circle
			(at 33.3502 3.24993)
			(size 1.0668 1.0668)
			(drill 0.7112)
			(layers "*.Cu" "*.Mask")
			(remove_unused_layers no)
			(net "GND")
			(clearance 0.1778)
			(thermal_gap 0.1778)
		)
		(pad "B45" thru_hole circle
			(at 34.34969 1.24968)
			(size 1.0668 1.0668)
			(drill 0.7112)
			(layers "*.Cu" "*.Mask")
			(remove_unused_layers no)
			(net "P3E_CPU0_PE1_PCH_CON_TXP<8>")
			(clearance 0.1778)
			(thermal_gap 0.1778)
		)
		(pad "B46" thru_hole circle
			(at 35.35045 3.24993)
			(size 1.0668 1.0668)
			(drill 0.7112)
			(layers "*.Cu" "*.Mask")
			(remove_unused_layers no)
			(net "P3E_CPU0_PE1_PCH_CON_TXN<8>")
			(clearance 0.1778)
			(thermal_gap 0.1778)
		)
		(pad "B47" thru_hole circle
			(at 36.34994 1.24968)
			(size 1.0668 1.0668)
			(drill 0.7112)
			(layers "*.Cu" "*.Mask")
			(remove_unused_layers no)
			(net "GND")
			(clearance 0.1778)
			(thermal_gap 0.1778)
		)
		(pad "B48" thru_hole circle
			(at 37.34943 3.24993)
			(size 1.0668 1.0668)
			(drill 0.7112)
			(layers "*.Cu" "*.Mask")
			(remove_unused_layers no)
			(net "PCIE_SLOT2_PRSNT2_3_N")
			(clearance 0.1778)
			(thermal_gap 0.1778)
		)
		(pad "B49" thru_hole circle
			(at 38.35019 1.24968)
			(size 1.0668 1.0668)
			(drill 0.7112)
			(layers "*.Cu" "*.Mask")
			(remove_unused_layers no)
			(net "GND")
			(clearance 0.1778)
			(thermal_gap 0.1778)
		)
		(pad "B50" thru_hole circle
			(at 39.34968 3.24993)
			(size 1.0668 1.0668)
			(drill 0.7112)
			(layers "*.Cu" "*.Mask")
			(remove_unused_layers no)
			(net "P3E_CPU0_PE1_SS_C_TXP<7>")
			(clearance 0.1778)
			(thermal_gap 0.1778)
		)
		(pad "B51" thru_hole circle
			(at 40.35044 1.24968)
			(size 1.0668 1.0668)
			(drill 0.7112)
			(layers "*.Cu" "*.Mask")
			(remove_unused_layers no)
			(net "P3E_CPU0_PE1_SS_C_TXN<7>")
			(clearance 0.1778)
			(thermal_gap 0.1778)
		)
		(pad "B52" thru_hole circle
			(at 41.34993 3.24993)
			(size 1.0668 1.0668)
			(drill 0.7112)
			(layers "*.Cu" "*.Mask")
			(remove_unused_layers no)
			(net "GND")
			(clearance 0.1778)
			(thermal_gap 0.1778)
		)
		(pad "B53" thru_hole circle
			(at 42.34942 1.24968)
			(size 1.0668 1.0668)
			(drill 0.7112)
			(layers "*.Cu" "*.Mask")
			(remove_unused_layers no)
			(net "GND")
			(clearance 0.1778)
			(thermal_gap 0.1778)
		)
		(pad "B54" thru_hole circle
			(at 43.35018 3.24993)
			(size 1.0668 1.0668)
			(drill 0.7112)
			(layers "*.Cu" "*.Mask")
			(remove_unused_layers no)
			(net "P3E_CPU0_PE1_SS_C_TXP<6>")
			(clearance 0.1778)
			(thermal_gap 0.1778)
		)
		(pad "B55" thru_hole circle
			(at 44.34967 1.24968)
			(size 1.0668 1.0668)
			(drill 0.7112)
			(layers "*.Cu" "*.Mask")
			(remove_unused_layers no)
			(net "P3E_CPU0_PE1_SS_C_TXN<6>")
			(clearance 0.1778)
			(thermal_gap 0.1778)
		)
		(pad "B56" thru_hole circle
			(at 45.35043 3.24993)
			(size 1.0668 1.0668)
			(drill 0.7112)
			(layers "*.Cu" "*.Mask")
			(remove_unused_layers no)
			(net "GND")
			(clearance 0.1778)
			(thermal_gap 0.1778)
		)
		(pad "B57" thru_hole circle
			(at 46.34992 1.24968)
			(size 1.0668 1.0668)
			(drill 0.7112)
			(layers "*.Cu" "*.Mask")
			(remove_unused_layers no)
			(net "GND")
			(clearance 0.1778)
			(thermal_gap 0.1778)
		)
		(pad "B58" thru_hole circle
			(at 47.34941 3.24993)
			(size 1.0668 1.0668)
			(drill 0.7112)
			(layers "*.Cu" "*.Mask")
			(remove_unused_layers no)
			(net "P3E_CPU0_PE1_SS_C_TXP<5>")
			(clearance 0.1778)
			(thermal_gap 0.1778)
		)
		(pad "B59" thru_hole circle
			(at 48.35017 1.24968)
			(size 1.0668 1.0668)
			(drill 0.7112)
			(layers "*.Cu" "*.Mask")
			(remove_unused_layers no)
			(net "P3E_CPU0_PE1_SS_C_TXN<5>")
			(clearance 0.1778)
			(thermal_gap 0.1778)
		)
		(pad "B60" thru_hole circle
			(at 49.34966 3.24993)
			(size 1.0668 1.0668)
			(drill 0.7112)
			(layers "*.Cu" "*.Mask")
			(remove_unused_layers no)
			(net "GND")
			(clearance 0.1778)
			(thermal_gap 0.1778)
		)
		(pad "B61" thru_hole circle
			(at 50.35042 1.24968)
			(size 1.0668 1.0668)
			(drill 0.7112)
			(layers "*.Cu" "*.Mask")
			(remove_unused_layers no)
			(net "GND")
			(clearance 0.1778)
			(thermal_gap 0.1778)
		)
		(pad "B62" thru_hole circle
			(at 51.34991 3.24993)
			(size 1.0668 1.0668)
			(drill 0.7112)
			(layers "*.Cu" "*.Mask")
			(remove_unused_layers no)
			(net "P3E_CPU0_PE1_SS_C_TXP<4>")
			(clearance 0.1778)
			(thermal_gap 0.1778)
		)
		(pad "B63" thru_hole circle
			(at 52.3494 1.24968)
			(size 1.0668 1.0668)
			(drill 0.7112)
			(layers "*.Cu" "*.Mask")
			(remove_unused_layers no)
			(net "P3E_CPU0_PE1_SS_C_TXN<4>")
			(clearance 0.1778)
			(thermal_gap 0.1778)
		)
		(pad "B64" thru_hole circle
			(at 53.35016 3.24993)
			(size 1.0668 1.0668)
			(drill 0.7112)
			(layers "*.Cu" "*.Mask")
			(remove_unused_layers no)
			(net "GND")
			(clearance 0.1778)
			(thermal_gap 0.1778)
		)
		(pad "B65" thru_hole circle
			(at 54.34965 1.24968)
			(size 1.0668 1.0668)
			(drill 0.7112)
			(layers "*.Cu" "*.Mask")
			(remove_unused_layers no)
			(net "GND")
			(clearance 0.1778)
			(thermal_gap 0.1778)
		)
		(pad "B66" thru_hole circle
			(at 55.35041 3.24993)
			(size 1.0668 1.0668)
			(drill 0.7112)
			(layers "*.Cu" "*.Mask")
			(remove_unused_layers no)
			(net "P3E_CPU0_PE1_SS_C_TXP<3>")
			(clearance 0.1778)
			(thermal_gap 0.1778)
		)
	)
)
